M48
;Layer_Color=9474304
;FILE_FORMAT=4:4
METRIC,LZ
;TYPE=PLATED
T1F00S00C0.2540
T2F00S00C3.5000
%
T01
X00033Y00031
Y00038
X0003288Y00045166
X00033Y00051645
X00037Y00064
X00037758Y00073
X00080512Y00067616
X00090162Y00085574
X00093057Y00101595
X00094793Y00112219
X00104Y00107
X00126Y001
X00154373Y00105997
X00166Y00112
X00167Y0012
X00168Y00131
X00145027Y0014518
X00148849Y00161221
X00138262Y00162104
X00128214Y00138
X00115Y00139
Y00146
X00106178Y00147
X00091831Y00146884
X00083Y00146
X00083228Y00162104
X00079Y001946
Y002156
Y002366
Y00257
X00058
Y002366
Y002156
Y001946
X00037
Y002156
Y002366
Y00257
X001Y002564
Y00236
Y00215
Y00194
X00121Y001946
Y002156
Y002366
Y00257
X00142
Y002366
Y002156
Y001946
X00163
Y002156
Y002366
Y00257
X00184Y00257
Y002366
Y002156
Y001946
X0021Y001921
Y001811
Y002031
Y002141
Y002361
Y002581
X00181826Y00161442
X00201Y0012
X00204Y00111
X00207Y00077
X00198
X00197Y00052
X00206
X00204Y00040054
X00211156Y0003862
X00191Y00037
X00190545Y00043935
X00176Y00044
X00152Y00036
X00137
X00123Y00035
X00111
X00093Y00034
X00063Y00038
X00065988Y00100369
X00066Y00112
X00076611Y00127172
X00053051Y00126729
X00052102Y00139442
X00039452Y00130651
X00041792Y00117242
X00106948Y00062472
X00012Y00065
Y00074
X00015Y00050312
X00006826
X00006395Y00041971
X00012791Y00042
X00011Y00339
Y00349
X00018519Y00343994
X00026Y00349
X00023386Y00401023
X0001743Y00401507
X00011151Y00401828
X00014291Y00409878
X00031414Y00403184
X00068713Y00403287
X0006759Y0039752
X0007775Y0040768
Y0038736
X0009807
X0011839
X0012855
X0013871
X0014887
X0015903
Y003772
Y0035688
Y0034672
Y0033656
X00149024Y00334175
X00137823Y00333314
X00126909Y00334032
X0014887Y0034672
X0017935
X0018951
X0019967
X0020983
Y0035688
Y0036704
Y003772
Y0038736
Y0039752
Y0040768
X0019967
Y0039752
Y0038736
Y003772
Y0036704
Y0035688
X0018951
Y0036704
X0017935
Y0035688
Y0033656
X0018951
X0019967
X0020983
Y003264
X0019967
X0018951
X00184Y002996
Y002786
X00163Y002786
Y002996
X00142
Y002786
X00121
Y002996
X001Y00299
X0008791Y0030608
X00079Y002996
X0006759Y0029592
Y0030608
X00058Y002996
Y002786
X0006759Y002756
Y0028576
X00079Y002786
X001Y00278
X00037Y002786
Y002996
X00049915Y00341352
X00053974Y00359649
X00051Y00371
X00050396Y00377474
X00039824Y00361855
X0007775Y0035688
X0013871Y0039752
X0016919Y0040768
X0018951Y0038736
X0021Y003131
Y003021
T02
X0011Y0042
M30
